(kicad_pcb
	(version 20241229)
	(generator "pcbnew")
	(generator_version "9.0")
	(general
		(thickness 1.711)
		(legacy_teardrops no)
	)
	(paper "A4")
	(title_block
		(title "Antmicro Baseboard for Jetson AGX Thor")
		(date "2026-02-18")
		(rev "1.1.0")
		(company "Antmicro Ltd")
		(comment 1 "www.antmicro.com")
		(comment 9 "footprints 571-575 of 1170")
	)
	(layers
		(0 "F.Cu" signal)
		(4 "In1.Cu" signal)
		(6 "In2.Cu" signal)
		(8 "In3.Cu" signal)
		(10 "In4.Cu" jumper)
		(12 "In5.Cu" signal)
		(14 "In6.Cu" signal)
		(16 "In7.Cu" signal)
		(18 "In8.Cu" signal)
		(2 "B.Cu" signal)
		(9 "F.Adhes" user "F.Adhesive")
		(11 "B.Adhes" user "B.Adhesive")
		(13 "F.Paste" user)
		(15 "B.Paste" user)
		(5 "F.SilkS" user "F.Silkscreen")
		(7 "B.SilkS" user "B.Silkscreen")
		(1 "F.Mask" user)
		(3 "B.Mask" user)
		(17 "Dwgs.User" user "User.Drawings")
		(19 "Cmts.User" user "User.Comments")
		(21 "Eco1.User" user "User.Eco1")
		(23 "Eco2.User" user "User.Eco2")
		(25 "Edge.Cuts" user)
		(27 "Margin" user)
		(31 "F.CrtYd" user "F.Courtyard")
		(29 "B.CrtYd" user "B.Courtyard")
		(35 "F.Fab" user)
		(33 "B.Fab" user)
	)
	(footprint "antmicro-footprints:C_0402_1005Metric"
		(layer "F.Cu")
		(at 212.544132 84.292 -90)
		(descr "Capacitor SMD 0402")
		(tags "capacitor SMD 0402")
		(property "Reference" "C128"
			(at -3.682 0.324132 90)
			(layer "F.SilkS")
			(effects
				(font
					(size 0.7 0.7)
					(thickness 0.15)
				)
				(justify right top)
			)
		)
		(property "Value" "C_100n_0402"
			(at -1.022927 2.155213 90)
			(layer "F.Fab")
			(effects
				(font
					(size 0.7 0.7)
					(thickness 0.15)
				)
				(justify right top)
			)
		)
		(property "Datasheet" "https://www.murata.com/products/productdetail?partno=GRM155R61H104KE14%23"
			(at 0 0 90)
			(layer "F.Fab")
			(hide yes)
			(effects
				(font
					(size 1.27 1.27)
					(thickness 0.15)
				)
			)
		)
		(property "Description" "SMD Multilayer Ceramic Capacitor, 0.1 µF, 50 V, 0402 [1005 Metric], ± 10%, X5R, GRM Series"
			(at 0 0 90)
			(layer "F.Fab")
			(hide yes)
			(effects
				(font
					(size 1.27 1.27)
					(thickness 0.15)
				)
			)
		)
		(property "Manufacturer" "Murata"
			(at 0 0 270)
			(unlocked yes)
			(layer "F.Fab")
			(hide yes)
			(effects
				(font
					(size 1 1)
					(thickness 0.15)
				)
			)
		)
		(property "MPN" "GRM155R61H104KE14D"
			(at 0 0 270)
			(unlocked yes)
			(layer "F.Fab")
			(hide yes)
			(effects
				(font
					(size 1 1)
					(thickness 0.15)
				)
			)
		)
		(property "Val" "100n"
			(at 0 0 270)
			(unlocked yes)
			(layer "F.Fab")
			(hide yes)
			(effects
				(font
					(size 1 1)
					(thickness 0.15)
				)
			)
		)
		(property "License" "Apache-2.0"
			(at 0 0 270)
			(unlocked yes)
			(layer "F.Fab")
			(hide yes)
			(effects
				(font
					(size 1 1)
					(thickness 0.15)
				)
			)
		)
		(property "Author" "Antmicro"
			(at 0 0 270)
			(unlocked yes)
			(layer "F.Fab")
			(hide yes)
			(effects
				(font
					(size 1 1)
					(thickness 0.15)
				)
			)
		)
		(property "Voltage" "50V"
			(at 0 0 270)
			(unlocked yes)
			(layer "F.Fab")
			(hide yes)
			(effects
				(font
					(size 1 1)
					(thickness 0.15)
				)
			)
		)
		(property "Dielectric" "X5R"
			(at 0 0 270)
			(unlocked yes)
			(layer "F.Fab")
			(hide yes)
			(effects
				(font
					(size 1 1)
					(thickness 0.15)
				)
			)
		)
		(sheetname "/USB DP Alt mode/")
		(sheetfile "usb_dp.kicad_sch")
		(attr smd)
		(fp_rect
			(start -0.925 -0.47)
			(end 0.925 0.47)
			(stroke
				(width 0.05)
				(type default)
			)
			(fill no)
			(layer "F.CrtYd")
		)
		(fp_line
			(start -0.494 0.248)
			(end -0.494 -0.25)
			(stroke
				(width 0.15)
				(type solid)
			)
			(layer "F.Fab")
		)
		(fp_line
			(start 0.504 0.248)
			(end -0.494 0.248)
			(stroke
				(width 0.15)
				(type solid)
			)
			(layer "F.Fab")
		)
		(fp_line
			(start -0.494 -0.25)
			(end 0.504 -0.25)
			(stroke
				(width 0.15)
				(type solid)
			)
			(layer "F.Fab")
		)
		(fp_line
			(start 0.504 -0.25)
			(end 0.504 0.248)
			(stroke
				(width 0.15)
				(type solid)
			)
			(layer "F.Fab")
		)
		(fp_text user "Author: Antmicro"
			(at -0.939 3.399 90)
			(layer "F.Fab")
			(effects
				(font
					(size 0.7 0.7)
					(thickness 0.15)
				)
				(justify right top)
			)
		)
		(fp_text user "${REFERENCE}"
			(at -0.939 4.599 90)
			(layer "F.Fab")
			(effects
				(font
					(size 0.7 0.7)
					(thickness 0.15)
				)
				(justify right top)
			)
		)
		(fp_text user "License: Apache-2.0"
			(at -0.939 5.799 90)
			(layer "F.Fab")
			(effects
				(font
					(size 0.7 0.7)
					(thickness 0.15)
				)
				(justify right top)
			)
		)
		(pad "1" smd roundrect
			(at -0.48 0 270)
			(size 0.59 0.64)
			(layers "F.Cu" "F.Mask" "F.Paste")
			(roundrect_rratio 0.25)
			(net 329 "/SoM_IO2/USBSS1.TX-")
			(pintype "passive")
		)
		(pad "2" smd roundrect
			(at 0.48 0 270)
			(size 0.59 0.64)
			(layers "F.Cu" "F.Mask" "F.Paste")
			(roundrect_rratio 0.25)
			(net 310 "/USB DP Alt mode/USBSS1_TX_C_P")
			(pintype "passive")
		)
	)
	(footprint "antmicro-footprints:C_0402_1005Metric"
		(layer "F.Cu")
		(at 207.34 117.8 -90)
		(descr "Capacitor SMD 0402")
		(tags "capacitor SMD 0402")
		(property "Reference" "C95"
			(at -3 0.44 90)
			(layer "F.SilkS")
			(effects
				(font
					(size 0.7 0.7)
					(thickness 0.15)
				)
				(justify right top)
			)
		)
		(property "Value" "C_100n_0402"
			(at -1.022927 2.155213 90)
			(layer "F.Fab")
			(effects
				(font
					(size 0.7 0.7)
					(thickness 0.15)
				)
				(justify right top)
			)
		)
		(property "Datasheet" "https://www.murata.com/products/productdetail?partno=GRM155R61H104KE14%23"
			(at 0 0 90)
			(layer "F.Fab")
			(hide yes)
			(effects
				(font
					(size 1.27 1.27)
					(thickness 0.15)
				)
			)
		)
		(property "Description" "SMD Multilayer Ceramic Capacitor, 0.1 µF, 50 V, 0402 [1005 Metric], ± 10%, X5R, GRM Series"
			(at 0 0 90)
			(layer "F.Fab")
			(hide yes)
			(effects
				(font
					(size 1.27 1.27)
					(thickness 0.15)
				)
			)
		)
		(property "MPN" "GRM155R61H104KE14D"
			(at 0 0 270)
			(unlocked yes)
			(layer "F.Fab")
			(hide yes)
			(effects
				(font
					(size 1 1)
					(thickness 0.15)
				)
			)
		)
		(property "Val" "100n"
			(at 0 0 270)
			(unlocked yes)
			(layer "F.Fab")
			(hide yes)
			(effects
				(font
					(size 1 1)
					(thickness 0.15)
				)
			)
		)
		(property "Voltage" "50V"
			(at 0 0 270)
			(unlocked yes)
			(layer "F.Fab")
			(hide yes)
			(effects
				(font
					(size 1 1)
					(thickness 0.15)
				)
			)
		)
		(property "Dielectric" "X5R"
			(at 0 0 270)
			(unlocked yes)
			(layer "F.Fab")
			(hide yes)
			(effects
				(font
					(size 1 1)
					(thickness 0.15)
				)
			)
		)
		(property "Manufacturer" "Murata"
			(at 0 0 270)
			(unlocked yes)
			(layer "F.Fab")
			(hide yes)
			(effects
				(font
					(size 1 1)
					(thickness 0.15)
				)
			)
		)
		(property "License" "Apache-2.0"
			(at 0 0 270)
			(unlocked yes)
			(layer "F.Fab")
			(hide yes)
			(effects
				(font
					(size 1 1)
					(thickness 0.15)
				)
			)
		)
		(property "Author" "Antmicro"
			(at 0 0 270)
			(unlocked yes)
			(layer "F.Fab")
			(hide yes)
			(effects
				(font
					(size 1 1)
					(thickness 0.15)
				)
			)
		)
		(sheetname "/USB Hub/")
		(sheetfile "usb_hub.kicad_sch")
		(attr smd)
		(fp_poly
			(pts
				(xy -0.925 -0.47) (xy -0.925 0.47) (xy 0.925 0.47) (xy 0.925 -0.47)
			)
			(stroke
				(width 0.05)
				(type default)
			)
			(fill no)
			(layer "F.CrtYd")
		)
		(fp_line
			(start -0.494 0.248)
			(end -0.494 -0.25)
			(stroke
				(width 0.15)
				(type solid)
			)
			(layer "F.Fab")
		)
		(fp_line
			(start 0.504 0.248)
			(end -0.494 0.248)
			(stroke
				(width 0.15)
				(type solid)
			)
			(layer "F.Fab")
		)
		(fp_line
			(start -0.494 -0.25)
			(end 0.504 -0.25)
			(stroke
				(width 0.15)
				(type solid)
			)
			(layer "F.Fab")
		)
		(fp_line
			(start 0.504 -0.25)
			(end 0.504 0.248)
			(stroke
				(width 0.15)
				(type solid)
			)
			(layer "F.Fab")
		)
		(fp_text user "${REFERENCE}"
			(at -0.939 4.599 90)
			(layer "F.Fab")
			(effects
				(font
					(size 0.7 0.7)
					(thickness 0.15)
				)
				(justify right top)
			)
		)
		(fp_text user "License: Apache-2.0"
			(at -0.939 5.799 90)
			(layer "F.Fab")
			(effects
				(font
					(size 0.7 0.7)
					(thickness 0.15)
				)
				(justify right top)
			)
		)
		(fp_text user "Author: Antmicro"
			(at -0.939 3.399 90)
			(layer "F.Fab")
			(effects
				(font
					(size 0.7 0.7)
					(thickness 0.15)
				)
				(justify right top)
			)
		)
		(pad "1" smd roundrect
			(at -0.48 0 270)
			(size 0.59 0.64)
			(layers "F.Cu" "F.Mask" "F.Paste")
			(roundrect_rratio 0.25)
			(net 1 "GND")
			(pintype "passive")
		)
		(pad "2" smd roundrect
			(at 0.48 0 270)
			(size 0.59 0.64)
			(layers "F.Cu" "F.Mask" "F.Paste")
			(roundrect_rratio 0.25)
			(net 282 "+1V15")
			(pintype "passive")
		)
	)
	(footprint "antmicro-footprints:R_0402_1005Metric"
		(layer "F.Cu")
		(at 133.8 56.27 -90)
		(descr "Resistor SMD 0402")
		(tags "resistor SMD 0402")
		(property "Reference" "R75"
			(at 0.26 -10.78 90)
			(layer "F.SilkS")
			(effects
				(font
					(size 0.7 0.7)
					(thickness 0.15)
				)
				(justify right top)
			)
		)
		(property "Value" "R_49k9_0402"
			(at -1.011843 1.772047 90)
			(layer "F.Fab")
			(effects
				(font
					(size 0.7 0.7)
					(thickness 0.15)
				)
				(justify right top)
			)
		)
		(property "Datasheet" "https://www.bourns.com/docs/product-datasheets/cr.pdf"
			(at 0 0 90)
			(layer "F.Fab")
			(hide yes)
			(effects
				(font
					(size 1.27 1.27)
					(thickness 0.15)
				)
			)
		)
		(property "Description" "SMD Chip Resistor, 49.9 kohm, ± 1%, 63 mW, 0402 [1005 Metric], Thick Film, General Purpose"
			(at 0 0 90)
			(layer "F.Fab")
			(hide yes)
			(effects
				(font
					(size 1.27 1.27)
					(thickness 0.15)
				)
			)
		)
		(property "MPN" "CR0402-FX-4992GLF"
			(at 0 0 270)
			(unlocked yes)
			(layer "F.Fab")
			(hide yes)
			(effects
				(font
					(size 1 1)
					(thickness 0.15)
				)
			)
		)
		(property "Manufacturer" "Bourns"
			(at 0 0 270)
			(unlocked yes)
			(layer "F.Fab")
			(hide yes)
			(effects
				(font
					(size 1 1)
					(thickness 0.15)
				)
			)
		)
		(property "License" "Apache-2.0"
			(at 0 0 270)
			(unlocked yes)
			(layer "F.Fab")
			(hide yes)
			(effects
				(font
					(size 1 1)
					(thickness 0.15)
				)
			)
		)
		(property "Author" "Antmicro"
			(at 0 0 270)
			(unlocked yes)
			(layer "F.Fab")
			(hide yes)
			(effects
				(font
					(size 1 1)
					(thickness 0.15)
				)
			)
		)
		(property "Val" "49k9"
			(at 0 0 270)
			(unlocked yes)
			(layer "F.Fab")
			(hide yes)
			(effects
				(font
					(size 1 1)
					(thickness 0.15)
				)
			)
		)
		(property "Tolerance" "1%"
			(at 0 0 270)
			(unlocked yes)
			(layer "F.Fab")
			(hide yes)
			(effects
				(font
					(size 1 1)
					(thickness 0.15)
				)
			)
		)
		(sheetname "/DCDC/")
		(sheetfile "dcdc.kicad_sch")
		(attr smd)
		(fp_rect
			(start -0.925 -0.47)
			(end 0.925 0.47)
			(stroke
				(width 0.05)
				(type default)
			)
			(fill no)
			(layer "F.CrtYd")
		)
		(fp_rect
			(start -0.5 -0.25)
			(end 0.5 0.25)
			(stroke
				(width 0.15)
				(type solid)
			)
			(fill no)
			(layer "F.Fab")
		)
		(fp_text user "License: Apache-2.0"
			(at -0.95 5.169 90)
			(layer "F.Fab")
			(effects
				(font
					(size 0.7 0.7)
					(thickness 0.15)
				)
				(justify right top)
			)
		)
		(fp_text user "Author: Antmicro"
			(at -0.95 4.169 90)
			(layer "F.Fab")
			(effects
				(font
					(size 0.7 0.7)
					(thickness 0.15)
				)
				(justify right top)
			)
		)
		(fp_text user "${REFERENCE}"
			(at -0.95 3.168 90)
			(layer "F.Fab")
			(effects
				(font
					(size 0.7 0.7)
					(thickness 0.15)
				)
				(justify right top)
			)
		)
		(pad "1" smd roundrect
			(at -0.48 0 270)
			(size 0.59 0.64)
			(layers "F.Cu" "F.Mask" "F.Paste")
			(roundrect_rratio 0.25)
			(net 1305 "/DCDC/5V_{AON}_EN")
			(pintype "passive")
		)
		(pad "2" smd roundrect
			(at 0.48 0 270)
			(size 0.59 0.64)
			(layers "F.Cu" "F.Mask" "F.Paste")
			(roundrect_rratio 0.25)
			(net 13 "VCC")
			(pintype "passive")
		)
	)
	(footprint "antmicro-footprints:C_0402_1005Metric"
		(layer "F.Cu")
		(at 92 65.45)
		(descr "Capacitor SMD 0402")
		(tags "capacitor SMD 0402")
		(property "Reference" "C404"
			(at -0.4 1.3 0)
			(layer "F.SilkS")
			(effects
				(font
					(size 0.7 0.7)
					(thickness 0.15)
				)
				(justify left bottom)
			)
		)
		(property "Value" "C_1u_25V_0402"
			(at -1.022927 2.155213 0)
			(layer "F.Fab")
			(effects
				(font
					(size 0.7 0.7)
					(thickness 0.15)
				)
				(justify left bottom)
			)
		)
		(property "Datasheet" "https://www.murata.com/products/productdetail?partno=GRM155R61E105KE11%23"
			(at 0 0 0)
			(layer "F.Fab")
			(hide yes)
			(effects
				(font
					(size 1.27 1.27)
					(thickness 0.15)
				)
			)
		)
		(property "Description" "SMD Multilayer Ceramic Capacitor, 1 µF, 25 V, 0402 [1005 Metric], ± 10%, X5R, GRM Series"
			(at 0 0 0)
			(layer "F.Fab")
			(hide yes)
			(effects
				(font
					(size 1.27 1.27)
					(thickness 0.15)
				)
			)
		)
		(property "MPN" "GRM155R61E105KE11J"
			(at 0 0 0)
			(unlocked yes)
			(layer "F.Fab")
			(hide yes)
			(effects
				(font
					(size 1 1)
					(thickness 0.15)
				)
			)
		)
		(property "Manufacturer" "Murata"
			(at 0 0 0)
			(unlocked yes)
			(layer "F.Fab")
			(hide yes)
			(effects
				(font
					(size 1 1)
					(thickness 0.15)
				)
			)
		)
		(property "License" "Apache-2.0"
			(at 0 0 0)
			(unlocked yes)
			(layer "F.Fab")
			(hide yes)
			(effects
				(font
					(size 1 1)
					(thickness 0.15)
				)
			)
		)
		(property "Author" "Antmicro"
			(at 0 0 0)
			(unlocked yes)
			(layer "F.Fab")
			(hide yes)
			(effects
				(font
					(size 1 1)
					(thickness 0.15)
				)
			)
		)
		(property "Val" "1u"
			(at 0 0 0)
			(unlocked yes)
			(layer "F.Fab")
			(hide yes)
			(effects
				(font
					(size 1 1)
					(thickness 0.15)
				)
			)
		)
		(property "Voltage" "25V"
			(at 0 0 0)
			(unlocked yes)
			(layer "F.Fab")
			(hide yes)
			(effects
				(font
					(size 1 1)
					(thickness 0.15)
				)
			)
		)
		(property "Dielectric" "X5R"
			(at 0 0 0)
			(unlocked yes)
			(layer "F.Fab")
			(hide yes)
			(effects
				(font
					(size 1 1)
					(thickness 0.15)
				)
			)
		)
		(sheetname "/SoM_Power/")
		(sheetfile "som_power.kicad_sch")
		(attr smd)
		(fp_poly
			(pts
				(xy -0.925 -0.47) (xy 0.925 -0.47) (xy 0.925 0.47) (xy -0.925 0.47)
			)
			(stroke
				(width 0.05)
				(type default)
			)
			(fill no)
			(layer "F.CrtYd")
		)
		(fp_line
			(start -0.494 -0.25)
			(end 0.504 -0.25)
			(stroke
				(width 0.15)
				(type solid)
			)
			(layer "F.Fab")
		)
		(fp_line
			(start -0.494 0.248)
			(end -0.494 -0.25)
			(stroke
				(width 0.15)
				(type solid)
			)
			(layer "F.Fab")
		)
		(fp_line
			(start 0.504 -0.25)
			(end 0.504 0.248)
			(stroke
				(width 0.15)
				(type solid)
			)
			(layer "F.Fab")
		)
		(fp_line
			(start 0.504 0.248)
			(end -0.494 0.248)
			(stroke
				(width 0.15)
				(type solid)
			)
			(layer "F.Fab")
		)
		(fp_text user "${REFERENCE}"
			(at -0.939 4.599 0)
			(layer "F.Fab")
			(effects
				(font
					(size 0.7 0.7)
					(thickness 0.15)
				)
				(justify left bottom)
			)
		)
		(fp_text user "Author: Antmicro"
			(at -0.939 3.399 0)
			(layer "F.Fab")
			(effects
				(font
					(size 0.7 0.7)
					(thickness 0.15)
				)
				(justify left bottom)
			)
		)
		(fp_text user "License: Apache-2.0"
			(at -0.939 5.799 0)
			(layer "F.Fab")
			(effects
				(font
					(size 0.7 0.7)
					(thickness 0.15)
				)
				(justify left bottom)
			)
		)
		(pad "1" smd roundrect
			(at -0.48 0)
			(size 0.59 0.64)
			(layers "F.Cu" "F.Mask" "F.Paste")
			(roundrect_rratio 0.25)
			(net 1 "GND")
			(pintype "passive")
		)
		(pad "2" smd roundrect
			(at 0.48 0)
			(size 0.59 0.64)
			(layers "F.Cu" "F.Mask" "F.Paste")
			(roundrect_rratio 0.25)
			(net 1285 "/SoM_Power/VIN_PWR_ON")
			(pintype "passive")
		)
	)
	(footprint "antmicro-footprints:C_0402_1005Metric"
		(layer "F.Cu")
		(at 218.8 117.9 180)
		(descr "Capacitor SMD 0402")
		(tags "capacitor SMD 0402")
		(property "Reference" "C112"
			(at -1.005 2.4 0)
			(layer "F.SilkS")
			(effects
				(font
					(size 0.7 0.7)
					(thickness 0.15)
				)
				(justify right top)
			)
		)
		(property "Value" "C_100n_0402"
			(at -1.022927 2.155213 0)
			(layer "F.Fab")
			(effects
				(font
					(size 0.7 0.7)
					(thickness 0.15)
				)
				(justify right top)
			)
		)
		(property "Datasheet" "https://www.murata.com/products/productdetail?partno=GRM155R61H104KE14%23"
			(at 0 0 0)
			(layer "F.Fab")
			(hide yes)
			(effects
				(font
					(size 1.27 1.27)
					(thickness 0.15)
				)
			)
		)
		(property "Description" "SMD Multilayer Ceramic Capacitor, 0.1 µF, 50 V, 0402 [1005 Metric], ± 10%, X5R, GRM Series"
			(at 0 0 0)
			(layer "F.Fab")
			(hide yes)
			(effects
				(font
					(size 1.27 1.27)
					(thickness 0.15)
				)
			)
		)
		(property "Manufacturer" "Murata"
			(at 0 0 180)
			(unlocked yes)
			(layer "F.Fab")
			(hide yes)
			(effects
				(font
					(size 1 1)
					(thickness 0.15)
				)
			)
		)
		(property "MPN" "GRM155R61H104KE14D"
			(at 0 0 180)
			(unlocked yes)
			(layer "F.Fab")
			(hide yes)
			(effects
				(font
					(size 1 1)
					(thickness 0.15)
				)
			)
		)
		(property "Val" "100n"
			(at 0 0 180)
			(unlocked yes)
			(layer "F.Fab")
			(hide yes)
			(effects
				(font
					(size 1 1)
					(thickness 0.15)
				)
			)
		)
		(property "License" "Apache-2.0"
			(at 0 0 180)
			(unlocked yes)
			(layer "F.Fab")
			(hide yes)
			(effects
				(font
					(size 1 1)
					(thickness 0.15)
				)
			)
		)
		(property "Author" "Antmicro"
			(at 0 0 180)
			(unlocked yes)
			(layer "F.Fab")
			(hide yes)
			(effects
				(font
					(size 1 1)
					(thickness 0.15)
				)
			)
		)
		(property "Voltage" "50V"
			(at 0 0 180)
			(unlocked yes)
			(layer "F.Fab")
			(hide yes)
			(effects
				(font
					(size 1 1)
					(thickness 0.15)
				)
			)
		)
		(property "Dielectric" "X5R"
			(at 0 0 180)
			(unlocked yes)
			(layer "F.Fab")
			(hide yes)
			(effects
				(font
					(size 1 1)
					(thickness 0.15)
				)
			)
		)
		(sheetname "/USB Hub/")
		(sheetfile "usb_hub.kicad_sch")
		(attr smd)
		(fp_rect
			(start -0.925 -0.47)
			(end 0.925 0.47)
			(stroke
				(width 0.05)
				(type default)
			)
			(fill no)
			(layer "F.CrtYd")
		)
		(fp_line
			(start 0.504 0.248)
			(end -0.494 0.248)
			(stroke
				(width 0.15)
				(type solid)
			)
			(layer "F.Fab")
		)
		(fp_line
			(start 0.504 -0.25)
			(end 0.504 0.248)
			(stroke
				(width 0.15)
				(type solid)
			)
			(layer "F.Fab")
		)
		(fp_line
			(start -0.494 0.248)
			(end -0.494 -0.25)
			(stroke
				(width 0.15)
				(type solid)
			)
			(layer "F.Fab")
		)
		(fp_line
			(start -0.494 -0.25)
			(end 0.504 -0.25)
			(stroke
				(width 0.15)
				(type solid)
			)
			(layer "F.Fab")
		)
		(fp_text user "Author: Antmicro"
			(at -0.939 3.399 0)
			(layer "F.Fab")
			(effects
				(font
					(size 0.7 0.7)
					(thickness 0.15)
				)
				(justify right top)
			)
		)
		(fp_text user "${REFERENCE}"
			(at -0.939 4.599 0)
			(layer "F.Fab")
			(effects
				(font
					(size 0.7 0.7)
					(thickness 0.15)
				)
				(justify right top)
			)
		)
		(fp_text user "License: Apache-2.0"
			(at -0.939 5.799 0)
			(layer "F.Fab")
			(effects
				(font
					(size 0.7 0.7)
					(thickness 0.15)
				)
				(justify right top)
			)
		)
		(pad "1" smd roundrect
			(at -0.48 0 180)
			(size 0.59 0.64)
			(layers "F.Cu" "F.Mask" "F.Paste")
			(roundrect_rratio 0.25)
			(net 164 "/USB Hub/USBC3_CONN_TX1_P")
			(pintype "passive")
		)
		(pad "2" smd roundrect
			(at 0.48 0 180)
			(size 0.59 0.64)
			(layers "F.Cu" "F.Mask" "F.Paste")
			(roundrect_rratio 0.25)
			(net 283 "/USB Hub/USBC3_TX_{1}-")
			(pintype "passive")
		)
	)
)
